(kicad_pcb
	(version 20260206)
	(generator "pcbnew")
	(generator_version "10.0")
	(general
		(thickness 1.6)
		(legacy_teardrops no)
	)
	(paper "A4")
	(title_block
		(title "v1-pdb — T6M_PDB_D_0927_0900.brd")
		(comment 1 "Open CloudServer (Microsoft) / footprints 45-54 of 321")
	)
	(layers
		(0 "F.Cu" signal "TOP")
		(4 "In1.Cu" signal "GND")
		(6 "In2.Cu" signal "IN1")
		(8 "In3.Cu" signal "VCC")
		(10 "In4.Cu" signal "VCC1")
		(12 "In5.Cu" signal "IN2")
		(14 "In6.Cu" signal "GND1")
		(2 "B.Cu" signal "BOTTOM")
		(9 "F.Adhes" user "F.Adhesive")
		(11 "B.Adhes" user "B.Adhesive")
		(13 "F.Paste" user "Package Geometry/Pastemask Top")
		(15 "B.Paste" user "Package Geometry/Pastemask Bottom")
		(5 "F.SilkS" user "Ref Des/Silkscreen Top")
		(7 "B.SilkS" user "Ref Des/Silkscreen Bottom")
		(1 "F.Mask" user "Board Geometry/Soldermask Top")
		(3 "B.Mask" user "Board Geometry/Soldermask Bottom")
		(17 "Dwgs.User" user "User.Drawings")
		(19 "Cmts.User" user "User.Comments")
		(21 "Eco1.User" user "User.Eco1")
		(23 "Eco2.User" user "User.Eco2")
		(25 "Edge.Cuts" user "Board Geometry/Outline")
		(27 "Margin" user)
		(31 "F.CrtYd" user "Package Geometry/Place Bound Top")
		(29 "B.CrtYd" user "Package Geometry/Place Bound Bottom")
		(35 "F.Fab" user "Ref Des/Assembly Top")
		(33 "B.Fab" user "Ref Des/Assembly Bottom")
	)
	(footprint ""
		(layer "F.Cu")
		(at 25.997662 -8.344662)
		(property "Reference" "R43"
			(at -3.764788 0.113792 0)
			(unlocked yes)
			(layer "F.SilkS")
			(effects
				(font
					(size 0.7874 0.5842)
					(thickness 0.1524)
				)
				(justify left)
			)
		)
		(property "Value" ""
			(at 0 0 0)
			(layer "F.Fab")
			(effects
				(font
					(size 1.27 1.27)
				)
			)
		)
		(duplicate_pad_numbers_are_jumpers no)
		(fp_line
			(start -0.7874 -0.4064)
			(end 0.7874 -0.4064)
			(stroke
				(width 0.1524)
				(type default)
			)
			(layer "F.SilkS")
		)
		(fp_line
			(start -0.7874 0.4064)
			(end -0.7874 -0.4064)
			(stroke
				(width 0.1524)
				(type default)
			)
			(layer "F.SilkS")
		)
		(fp_line
			(start 0.7874 -0.4064)
			(end 0.7874 0.4064)
			(stroke
				(width 0.1524)
				(type default)
			)
			(layer "F.SilkS")
		)
		(fp_line
			(start 0.7874 0.4064)
			(end -0.7874 0.4064)
			(stroke
				(width 0.1524)
				(type default)
			)
			(layer "F.SilkS")
		)
		(fp_poly
			(pts
				(xy -0.508 0.2794) (xy -0.508 0.2286) (xy -0.635 0.2286) (xy -0.635 -0.254) (xy -0.5334 -0.254)
				(xy -0.5334 -0.2794) (xy 0.5334 -0.2794) (xy 0.5334 -0.254) (xy 0.635 -0.254) (xy 0.635 0.254) (xy 0.5334 0.254)
				(xy 0.5334 0.2794)
			)
			(stroke
				(width 0)
				(type default)
			)
			(fill no)
			(layer "F.CrtYd")
		)
		(pad "1" smd rect
			(at 0.40005 0)
			(size 0.4572 0.508)
			(layers "F.Cu" "F.Mask" "F.Paste")
			(net "PSU1_PS_KILL")
		)
		(pad "2" smd rect
			(at -0.40005 0)
			(size 0.4572 0.508)
			(layers "F.Cu" "F.Mask" "F.Paste")
			(net "GND")
		)
	)
	(footprint ""
		(layer "F.Cu")
		(at 91.399868 -420.06012)
		(property "Reference" "H15"
			(at -5.1308 -5.23113 0)
			(unlocked yes)
			(layer "F.SilkS")
			(effects
				(font
					(size 0.7874 0.5842)
					(thickness 0.1524)
				)
				(justify left)
			)
		)
		(property "Value" ""
			(at 0 0 0)
			(layer "F.Fab")
			(effects
				(font
					(size 1.27 1.27)
				)
			)
		)
		(duplicate_pad_numbers_are_jumpers no)
		(fp_circle
			(center 0 0)
			(end 4.826 0)
			(stroke
				(width 0.1524)
				(type default)
			)
			(fill no)
			(layer "F.SilkS")
		)
		(fp_circle
			(center 0 0)
			(end 4.826 0)
			(stroke
				(width 0.1524)
				(type default)
			)
			(fill no)
			(layer "B.SilkS")
		)
		(fp_poly
			(pts
				(arc
					(start 0 4.0132)
					(mid 0 -4.0132)
					(end 0 4.0132)
				)
			)
			(stroke
				(width 0)
				(type default)
			)
			(fill no)
			(layer "F.CrtYd")
		)
		(pad "" np_thru_hole circle
			(at 0 0)
			(size 8.001 8.001)
			(drill 8.001)
			(layers "*.Cu" "*.Mask")
			(clearance 0.381)
			(thermal_gap 0.381)
		)
		(zone
			(layers "F.Cu" "B.Cu" "In1.Cu" "In2.Cu" "In3.Cu" "In4.Cu" "In5.Cu" "In6.Cu")
			(hatch none 0.5)
			(connect_pads
				(clearance 0)
			)
			(min_thickness 0.25)
			(keepout
				(tracks not_allowed)
				(vias allowed)
				(pads allowed)
				(copperpour not_allowed)
				(footprints allowed)
			)
			(placement
				(enabled no)
				(sheetname "")
			)
			(fill
				(thermal_gap 0.5)
				(thermal_bridge_width 0.5)
				(island_removal_mode 0)
			)
			(polygon
				(pts
					(arc
						(start 91.399868 -415.53892)
						(mid 91.399868 -424.58132)
						(end 91.399868 -415.53892)
					)
				)
			)
		)
	)
	(footprint ""
		(layer "F.Cu")
		(at 25.931622 -94.464886)
		(property "Reference" "R69"
			(at -4.080256 -0.075692 0)
			(unlocked yes)
			(layer "F.SilkS")
			(effects
				(font
					(size 0.7874 0.5842)
					(thickness 0.1524)
				)
				(justify left)
			)
		)
		(property "Value" ""
			(at 0 0 0)
			(layer "F.Fab")
			(effects
				(font
					(size 1.27 1.27)
				)
			)
		)
		(duplicate_pad_numbers_are_jumpers no)
		(fp_line
			(start -0.7874 -0.4064)
			(end 0.7874 -0.4064)
			(stroke
				(width 0.1524)
				(type default)
			)
			(layer "F.SilkS")
		)
		(fp_line
			(start -0.7874 0.4064)
			(end -0.7874 -0.4064)
			(stroke
				(width 0.1524)
				(type default)
			)
			(layer "F.SilkS")
		)
		(fp_line
			(start 0.7874 -0.4064)
			(end 0.7874 0.4064)
			(stroke
				(width 0.1524)
				(type default)
			)
			(layer "F.SilkS")
		)
		(fp_line
			(start 0.7874 0.4064)
			(end -0.7874 0.4064)
			(stroke
				(width 0.1524)
				(type default)
			)
			(layer "F.SilkS")
		)
		(fp_poly
			(pts
				(xy -0.508 0.2794) (xy -0.508 0.2286) (xy -0.635 0.2286) (xy -0.635 -0.254) (xy -0.5334 -0.254)
				(xy -0.5334 -0.2794) (xy 0.5334 -0.2794) (xy 0.5334 -0.254) (xy 0.635 -0.254) (xy 0.635 0.254) (xy 0.5334 0.254)
				(xy 0.5334 0.2794)
			)
			(stroke
				(width 0)
				(type default)
			)
			(fill no)
			(layer "F.CrtYd")
		)
		(pad "1" smd rect
			(at 0.40005 0)
			(size 0.4572 0.508)
			(layers "F.Cu" "F.Mask" "F.Paste")
			(net "PSU2_RESET")
		)
		(pad "2" smd rect
			(at -0.40005 0)
			(size 0.4572 0.508)
			(layers "F.Cu" "F.Mask" "F.Paste")
			(net "GND")
		)
	)
	(footprint ""
		(layer "F.Cu")
		(at 39.458392 -110.374176 90)
		(property "Reference" "R114"
			(at -2.70256 2.149348 90)
			(unlocked yes)
			(layer "F.SilkS")
			(effects
				(font
					(size 0.7874 0.5842)
					(thickness 0.1524)
				)
				(justify left)
			)
		)
		(property "Value" ""
			(at 0 0 90)
			(layer "F.Fab")
			(effects
				(font
					(size 1.27 1.27)
				)
			)
		)
		(duplicate_pad_numbers_are_jumpers no)
		(fp_line
			(start 0.7874 -0.4064)
			(end 0.7874 0.4064)
			(stroke
				(width 0.1524)
				(type default)
			)
			(layer "F.SilkS")
		)
		(fp_line
			(start -0.7874 -0.4064)
			(end 0.7874 -0.4064)
			(stroke
				(width 0.1524)
				(type default)
			)
			(layer "F.SilkS")
		)
		(fp_line
			(start 0.7874 0.4064)
			(end -0.7874 0.4064)
			(stroke
				(width 0.1524)
				(type default)
			)
			(layer "F.SilkS")
		)
		(fp_line
			(start -0.7874 0.4064)
			(end -0.7874 -0.4064)
			(stroke
				(width 0.1524)
				(type default)
			)
			(layer "F.SilkS")
		)
		(fp_poly
			(pts
				(xy -0.508 0.2794) (xy -0.508 0.2286) (xy -0.635 0.2286) (xy -0.635 -0.254) (xy -0.5334 -0.254)
				(xy -0.5334 -0.2794) (xy 0.5334 -0.2794) (xy 0.5334 -0.254) (xy 0.635 -0.254) (xy 0.635 0.254) (xy 0.5334 0.254)
				(xy 0.5334 0.2794)
			)
			(stroke
				(width 0)
				(type default)
			)
			(fill no)
			(layer "F.CrtYd")
		)
		(pad "1" smd rect
			(at 0.40005 0 90)
			(size 0.4572 0.508)
			(layers "F.Cu" "F.Mask" "F.Paste")
			(net "PSU2_REMOTE_P")
		)
		(pad "2" smd rect
			(at -0.40005 0 90)
			(size 0.4572 0.508)
			(layers "F.Cu" "F.Mask" "F.Paste")
			(net "PSU2_REMOTE_R2_P")
		)
	)
	(footprint ""
		(layer "F.Cu")
		(at 81.78927 -14.939772 -90)
		(property "Reference" "C7"
			(at -1.75133 -0.093726 90)
			(unlocked yes)
			(layer "F.SilkS")
			(effects
				(font
					(size 0.7874 0.5842)
					(thickness 0.1524)
				)
				(justify left)
			)
		)
		(property "Value" ""
			(at 0 0 270)
			(layer "F.Fab")
			(effects
				(font
					(size 1.27 1.27)
				)
			)
		)
		(duplicate_pad_numbers_are_jumpers no)
		(fp_line
			(start -0.7874 0.4064)
			(end -0.7874 -0.4064)
			(stroke
				(width 0.1524)
				(type default)
			)
			(layer "F.SilkS")
		)
		(fp_line
			(start 0.7874 0.4064)
			(end -0.7874 0.4064)
			(stroke
				(width 0.1524)
				(type default)
			)
			(layer "F.SilkS")
		)
		(fp_line
			(start 0 0.381)
			(end 0 -0.381)
			(stroke
				(width 0.1524)
				(type default)
			)
			(layer "F.SilkS")
		)
		(fp_line
			(start -0.7874 -0.4064)
			(end 0.7874 -0.4064)
			(stroke
				(width 0.1524)
				(type default)
			)
			(layer "F.SilkS")
		)
		(fp_line
			(start 0.7874 -0.4064)
			(end 0.7874 0.4064)
			(stroke
				(width 0.1524)
				(type default)
			)
			(layer "F.SilkS")
		)
		(fp_poly
			(pts
				(xy -0.5334 0.254) (xy -0.635 0.254) (xy -0.635 0.2286) (xy -0.635 -0.254) (xy -0.5334 -0.254) (xy -0.5334 -0.2794)
				(xy 0.5334 -0.2794) (xy 0.5334 -0.254) (xy 0.635 -0.254) (xy 0.635 0.254) (xy 0.5334 0.254) (xy 0.5334 0.2794)
				(xy -0.508 0.2794) (xy -0.5334 0.2794)
			)
			(stroke
				(width 0)
				(type default)
			)
			(fill no)
			(layer "F.CrtYd")
		)
		(pad "1" smd rect
			(at 0.40005 0 270)
			(size 0.4572 0.508)
			(layers "F.Cu" "F.Mask" "F.Paste")
			(net "P12V")
		)
		(pad "2" smd rect
			(at -0.40005 0 270)
			(size 0.4572 0.508)
			(layers "F.Cu" "F.Mask" "F.Paste")
			(net "GND")
		)
	)
	(footprint ""
		(layer "F.Cu")
		(at 40.157654 -14.412976 180)
		(property "Reference" "R9"
			(at 0.747014 1.214628 0)
			(unlocked yes)
			(layer "F.SilkS")
			(effects
				(font
					(size 0.7874 0.5842)
					(thickness 0.1524)
				)
				(justify left)
			)
		)
		(property "Value" ""
			(at 0 0 180)
			(layer "F.Fab")
			(effects
				(font
					(size 1.27 1.27)
				)
			)
		)
		(duplicate_pad_numbers_are_jumpers no)
		(fp_line
			(start 0.7874 0.4064)
			(end -0.7874 0.4064)
			(stroke
				(width 0.1524)
				(type default)
			)
			(layer "F.SilkS")
		)
		(fp_line
			(start 0.7874 -0.4064)
			(end 0.7874 0.4064)
			(stroke
				(width 0.1524)
				(type default)
			)
			(layer "F.SilkS")
		)
		(fp_line
			(start -0.7874 0.4064)
			(end -0.7874 -0.4064)
			(stroke
				(width 0.1524)
				(type default)
			)
			(layer "F.SilkS")
		)
		(fp_line
			(start -0.7874 -0.4064)
			(end 0.7874 -0.4064)
			(stroke
				(width 0.1524)
				(type default)
			)
			(layer "F.SilkS")
		)
		(fp_poly
			(pts
				(xy -0.508 0.2794) (xy -0.508 0.2286) (xy -0.635 0.2286) (xy -0.635 -0.254) (xy -0.5334 -0.254)
				(xy -0.5334 -0.2794) (xy 0.5334 -0.2794) (xy 0.5334 -0.254) (xy 0.635 -0.254) (xy 0.635 0.254) (xy 0.5334 0.254)
				(xy 0.5334 0.2794)
			)
			(stroke
				(width 0)
				(type default)
			)
			(fill no)
			(layer "F.CrtYd")
		)
		(pad "1" smd rect
			(at 0.40005 0 180)
			(size 0.4572 0.508)
			(layers "F.Cu" "F.Mask" "F.Paste")
			(net "PSU1_RETURN")
		)
		(pad "2" smd rect
			(at -0.40005 0 180)
			(size 0.4572 0.508)
			(layers "F.Cu" "F.Mask" "F.Paste")
			(net "GND")
		)
	)
	(footprint ""
		(layer "F.Cu")
		(at 72.185276 -307.819806 90)
		(property "Reference" "C55"
			(at -1.265682 5.175758 90)
			(unlocked yes)
			(layer "F.SilkS")
			(effects
				(font
					(size 0.7874 0.5842)
					(thickness 0.1524)
				)
				(justify left)
			)
		)
		(property "Value" ""
			(at 0 0 90)
			(layer "F.Fab")
			(effects
				(font
					(size 1.27 1.27)
				)
			)
		)
		(duplicate_pad_numbers_are_jumpers no)
		(fp_line
			(start 0.7874 -0.4064)
			(end 0.7874 0.4064)
			(stroke
				(width 0.1524)
				(type default)
			)
			(layer "F.SilkS")
		)
		(fp_line
			(start -0.7874 -0.4064)
			(end 0.7874 -0.4064)
			(stroke
				(width 0.1524)
				(type default)
			)
			(layer "F.SilkS")
		)
		(fp_line
			(start 0 0.381)
			(end 0 -0.381)
			(stroke
				(width 0.1524)
				(type default)
			)
			(layer "F.SilkS")
		)
		(fp_line
			(start 0.7874 0.4064)
			(end -0.7874 0.4064)
			(stroke
				(width 0.1524)
				(type default)
			)
			(layer "F.SilkS")
		)
		(fp_line
			(start -0.7874 0.4064)
			(end -0.7874 -0.4064)
			(stroke
				(width 0.1524)
				(type default)
			)
			(layer "F.SilkS")
		)
		(fp_poly
			(pts
				(xy -0.5334 0.254) (xy -0.635 0.254) (xy -0.635 0.2286) (xy -0.635 -0.254) (xy -0.5334 -0.254) (xy -0.5334 -0.2794)
				(xy 0.5334 -0.2794) (xy 0.5334 -0.254) (xy 0.635 -0.254) (xy 0.635 0.254) (xy 0.5334 0.254) (xy 0.5334 0.2794)
				(xy -0.508 0.2794) (xy -0.5334 0.2794)
			)
			(stroke
				(width 0)
				(type default)
			)
			(fill no)
			(layer "F.CrtYd")
		)
		(pad "1" smd rect
			(at 0.40005 0 90)
			(size 0.4572 0.508)
			(layers "F.Cu" "F.Mask" "F.Paste")
			(net "P12V")
		)
		(pad "2" smd rect
			(at -0.40005 0 90)
			(size 0.4572 0.508)
			(layers "F.Cu" "F.Mask" "F.Paste")
			(net "GND")
		)
	)
	(footprint ""
		(layer "F.Cu")
		(at 71.825104 -131.443476 90)
		(property "Reference" "C25"
			(at -3.902456 0.182626 90)
			(unlocked yes)
			(layer "F.SilkS")
			(effects
				(font
					(size 0.7874 0.5842)
					(thickness 0.1524)
				)
				(justify left)
			)
		)
		(property "Value" ""
			(at 0 0 90)
			(layer "F.Fab")
			(effects
				(font
					(size 1.27 1.27)
				)
			)
		)
		(duplicate_pad_numbers_are_jumpers no)
		(fp_line
			(start 0.7874 -0.4064)
			(end 0.7874 0.4064)
			(stroke
				(width 0.1524)
				(type default)
			)
			(layer "F.SilkS")
		)
		(fp_line
			(start -0.7874 -0.4064)
			(end 0.7874 -0.4064)
			(stroke
				(width 0.1524)
				(type default)
			)
			(layer "F.SilkS")
		)
		(fp_line
			(start 0 0.381)
			(end 0 -0.381)
			(stroke
				(width 0.1524)
				(type default)
			)
			(layer "F.SilkS")
		)
		(fp_line
			(start 0.7874 0.4064)
			(end -0.7874 0.4064)
			(stroke
				(width 0.1524)
				(type default)
			)
			(layer "F.SilkS")
		)
		(fp_line
			(start -0.7874 0.4064)
			(end -0.7874 -0.4064)
			(stroke
				(width 0.1524)
				(type default)
			)
			(layer "F.SilkS")
		)
		(fp_poly
			(pts
				(xy -0.5334 0.254) (xy -0.635 0.254) (xy -0.635 0.2286) (xy -0.635 -0.254) (xy -0.5334 -0.254) (xy -0.5334 -0.2794)
				(xy 0.5334 -0.2794) (xy 0.5334 -0.254) (xy 0.635 -0.254) (xy 0.635 0.254) (xy 0.5334 0.254) (xy 0.5334 0.2794)
				(xy -0.508 0.2794) (xy -0.5334 0.2794)
			)
			(stroke
				(width 0)
				(type default)
			)
			(fill no)
			(layer "F.CrtYd")
		)
		(pad "1" smd rect
			(at 0.40005 0 90)
			(size 0.4572 0.508)
			(layers "F.Cu" "F.Mask" "F.Paste")
			(net "P12V")
		)
		(pad "2" smd rect
			(at -0.40005 0 90)
			(size 0.4572 0.508)
			(layers "F.Cu" "F.Mask" "F.Paste")
			(net "GND")
		)
	)
	(footprint ""
		(layer "F.Cu")
		(at 69.726556 -175.945546 90)
		(property "Reference" "C34"
			(at -4.082034 0.14097 90)
			(unlocked yes)
			(layer "F.SilkS")
			(effects
				(font
					(size 0.7874 0.5842)
					(thickness 0.1524)
				)
				(justify left)
			)
		)
		(property "Value" ""
			(at 0 0 90)
			(layer "F.Fab")
			(effects
				(font
					(size 1.27 1.27)
				)
			)
		)
		(duplicate_pad_numbers_are_jumpers no)
		(fp_line
			(start 0.7874 -0.4064)
			(end 0.7874 0.4064)
			(stroke
				(width 0.1524)
				(type default)
			)
			(layer "F.SilkS")
		)
		(fp_line
			(start -0.7874 -0.4064)
			(end 0.7874 -0.4064)
			(stroke
				(width 0.1524)
				(type default)
			)
			(layer "F.SilkS")
		)
		(fp_line
			(start 0 0.381)
			(end 0 -0.381)
			(stroke
				(width 0.1524)
				(type default)
			)
			(layer "F.SilkS")
		)
		(fp_line
			(start 0.7874 0.4064)
			(end -0.7874 0.4064)
			(stroke
				(width 0.1524)
				(type default)
			)
			(layer "F.SilkS")
		)
		(fp_line
			(start -0.7874 0.4064)
			(end -0.7874 -0.4064)
			(stroke
				(width 0.1524)
				(type default)
			)
			(layer "F.SilkS")
		)
		(fp_poly
			(pts
				(xy -0.5334 0.254) (xy -0.635 0.254) (xy -0.635 0.2286) (xy -0.635 -0.254) (xy -0.5334 -0.254) (xy -0.5334 -0.2794)
				(xy 0.5334 -0.2794) (xy 0.5334 -0.254) (xy 0.635 -0.254) (xy 0.635 0.254) (xy 0.5334 0.254) (xy 0.5334 0.2794)
				(xy -0.508 0.2794) (xy -0.5334 0.2794)
			)
			(stroke
				(width 0)
				(type default)
			)
			(fill no)
			(layer "F.CrtYd")
		)
		(pad "1" smd rect
			(at 0.40005 0 90)
			(size 0.4572 0.508)
			(layers "F.Cu" "F.Mask" "F.Paste")
			(net "P12V")
		)
		(pad "2" smd rect
			(at -0.40005 0 90)
			(size 0.4572 0.508)
			(layers "F.Cu" "F.Mask" "F.Paste")
			(net "GND")
		)
	)
	(footprint ""
		(layer "F.Cu")
		(at 27.347672 -107.830366 90)
		(property "Reference" "R117"
			(at -3.30327 -1.060196 90)
			(unlocked yes)
			(layer "F.SilkS")
			(effects
				(font
					(size 0.7874 0.5842)
					(thickness 0.1524)
				)
				(justify left)
			)
		)
		(property "Value" ""
			(at 0 0 90)
			(layer "F.Fab")
			(effects
				(font
					(size 1.27 1.27)
				)
			)
		)
		(duplicate_pad_numbers_are_jumpers no)
		(fp_line
			(start 0.7874 -0.4064)
			(end 0.7874 0.4064)
			(stroke
				(width 0.1524)
				(type default)
			)
			(layer "F.SilkS")
		)
		(fp_line
			(start -0.7874 -0.4064)
			(end 0.7874 -0.4064)
			(stroke
				(width 0.1524)
				(type default)
			)
			(layer "F.SilkS")
		)
		(fp_line
			(start 0.7874 0.4064)
			(end -0.7874 0.4064)
			(stroke
				(width 0.1524)
				(type default)
			)
			(layer "F.SilkS")
		)
		(fp_line
			(start -0.7874 0.4064)
			(end -0.7874 -0.4064)
			(stroke
				(width 0.1524)
				(type default)
			)
			(layer "F.SilkS")
		)
		(fp_poly
			(pts
				(xy -0.508 0.2794) (xy -0.508 0.2286) (xy -0.635 0.2286) (xy -0.635 -0.254) (xy -0.5334 -0.254)
				(xy -0.5334 -0.2794) (xy 0.5334 -0.2794) (xy 0.5334 -0.254) (xy 0.635 -0.254) (xy 0.635 0.254) (xy 0.5334 0.254)
				(xy 0.5334 0.2794)
			)
			(stroke
				(width 0)
				(type default)
			)
			(fill no)
			(layer "F.CrtYd")
		)
		(pad "1" smd rect
			(at 0.40005 0 90)
			(size 0.4572 0.508)
			(layers "F.Cu" "F.Mask" "F.Paste")
			(net "PSU2_REMOTE_N")
		)
		(pad "2" smd rect
			(at -0.40005 0 90)
			(size 0.4572 0.508)
			(layers "F.Cu" "F.Mask" "F.Paste")
			(net "PSU2_REMOTE_R2_N")
		)
	)
)
